# T6G (Grand Teton) — schematic netlist excerpt (pin names and nets, part order shuffled) for the footprints in the layout excerpt that follows; sources: Cadence DE-HDL packaged netlist, KiCad conversion of 04192023_DAF0TMB3IC0_F0TG_MB_C_brd_V02_OCP.brd

R2905  Q_RES  0 5% CHIP  pkg 0402LF  page 240 : A = RST_SMB_SWITCH_N ; B = RST_SMB_SWITCH_R_N
C3932  Q_CAP  22UF 4V 20% X6S  pkg C0402  page 70 : A = PVDD11_S3_P0 ; B = GND
C6683  Q_CAP_DIFFBUS  DIFF BUS_0.22UF 6.3V 20% X6S  pkg C0201  page 330 : \1\ = P5E_CPU1_P1_TX_BUF_C_DP<11> ; \2\ = P5E_CPU1_P1_TX_BUF_DP<11>

(kicad_pcb
	(version 20260206)
	(generator "pcbnew")
	(generator_version "10.0")
	(general
		(thickness 1.6)
		(legacy_teardrops no)
	)
	(paper "A4")
	(title_block
		(title "04192023_DAF0TMB3IC0_F0TG_MB_C_brd_V02_OCP.brd")
		(comment 1 "Grand Teton / footprints 8132-8134 of 8354")
	)
	(layers
		(0 "F.Cu" signal "TOP")
		(4 "In1.Cu" signal "GND")
		(6 "In2.Cu" signal "IN1")
		(8 "In3.Cu" signal "GND1")
		(10 "In4.Cu" signal "IN2")
		(12 "In5.Cu" signal "GND2")
		(14 "In6.Cu" signal "IN3")
		(16 "In7.Cu" signal "GND3")
		(18 "In8.Cu" signal "VCC")
		(20 "In9.Cu" signal "VCC1")
		(22 "In10.Cu" signal "GND4")
		(24 "In11.Cu" signal "IN4")
		(26 "In12.Cu" signal "GND5")
		(28 "In13.Cu" signal "IN5")
		(30 "In14.Cu" signal "GND6")
		(32 "In15.Cu" signal "IN6")
		(34 "In16.Cu" signal "GND7")
		(2 "B.Cu" signal "BOTTOM")
		(9 "F.Adhes" user "F.Adhesive")
		(11 "B.Adhes" user "B.Adhesive")
		(13 "F.Paste" user "Package Geometry/Pastemask Top")
		(15 "B.Paste" user "Package Geometry/Pastemask Bottom")
		(5 "F.SilkS" user "Ref Des/Silkscreen Top")
		(7 "B.SilkS" user "Ref Des/Silkscreen Bottom")
		(1 "F.Mask" user "Board Geometry/Soldermask Top")
		(3 "B.Mask" user "Board Geometry/Soldermask Bottom")
		(17 "Dwgs.User" user "User.Drawings")
		(19 "Cmts.User" user "User.Comments")
		(21 "Eco1.User" user "User.Eco1")
		(23 "Eco2.User" user "User.Eco2")
		(25 "Edge.Cuts" user "Board Geometry/Outline")
		(27 "Margin" user)
		(31 "F.CrtYd" user "Package Geometry/Place Bound Top")
		(29 "B.CrtYd" user "Package Geometry/Place Bound Bottom")
		(35 "F.Fab" user "Ref Des/Assembly Top")
		(33 "B.Fab" user "Ref Des/Assembly Bottom")
	)
	(footprint ""
		(layer "B.Cu")
		(at 354.406454 -266.00531)
		(property "Reference" "C3932"
			(at 0 0 0)
			(layer "B.SilkS")
			(hide yes)
			(effects
				(font
					(size 1.27 1.27)
				)
				(justify mirror)
			)
		)
		(property "Value" ""
			(at 0 0 0)
			(layer "B.Fab")
			(effects
				(font
					(size 1.27 1.27)
				)
				(justify mirror)
			)
		)
		(duplicate_pad_numbers_are_jumpers no)
		(fp_line
			(start -0.7874 -0.4064)
			(end -0.7874 0.4064)
			(stroke
				(width 0.1524)
				(type default)
			)
			(layer "B.SilkS")
		)
		(fp_line
			(start -0.7874 0.4064)
			(end 0.7874 0.4064)
			(stroke
				(width 0.1524)
				(type default)
			)
			(layer "B.SilkS")
		)
		(fp_line
			(start 0.7874 -0.4064)
			(end -0.7874 -0.4064)
			(stroke
				(width 0.1524)
				(type default)
			)
			(layer "B.SilkS")
		)
		(fp_line
			(start 0.7874 0.4064)
			(end 0.7874 -0.4064)
			(stroke
				(width 0.1524)
				(type default)
			)
			(layer "B.SilkS")
		)
		(fp_line
			(start -0.67945 -0.3048)
			(end -0.67945 0.3048)
			(stroke
				(width 0.1)
				(type default)
			)
			(layer "B.Fab")
		)
		(fp_line
			(start -0.67945 0.3048)
			(end -0.120396 0.3048)
			(stroke
				(width 0.1)
				(type default)
			)
			(layer "B.Fab")
		)
		(fp_line
			(start -0.12065 -0.3048)
			(end -0.67945 -0.3048)
			(stroke
				(width 0.1)
				(type default)
			)
			(layer "B.Fab")
		)
		(fp_line
			(start -0.12065 -0.2794)
			(end -0.12065 -0.3048)
			(stroke
				(width 0.1)
				(type default)
			)
			(layer "B.Fab")
		)
		(fp_line
			(start -0.120396 0.2794)
			(end 0.12065 0.2794)
			(stroke
				(width 0.1)
				(type default)
			)
			(layer "B.Fab")
		)
		(fp_line
			(start -0.120396 0.3048)
			(end -0.120396 0.2794)
			(stroke
				(width 0.1)
				(type default)
			)
			(layer "B.Fab")
		)
		(fp_line
			(start 0.12065 -0.305054)
			(end 0.12065 -0.2794)
			(stroke
				(width 0.1)
				(type default)
			)
			(layer "B.Fab")
		)
		(fp_line
			(start 0.12065 -0.2794)
			(end -0.12065 -0.2794)
			(stroke
				(width 0.1)
				(type default)
			)
			(layer "B.Fab")
		)
		(fp_line
			(start 0.12065 0.2794)
			(end 0.12065 0.3048)
			(stroke
				(width 0.1)
				(type default)
			)
			(layer "B.Fab")
		)
		(fp_line
			(start 0.12065 0.3048)
			(end 0.67945 0.3048)
			(stroke
				(width 0.1)
				(type default)
			)
			(layer "B.Fab")
		)
		(fp_line
			(start 0.67945 -0.305054)
			(end 0.12065 -0.305054)
			(stroke
				(width 0.1)
				(type default)
			)
			(layer "B.Fab")
		)
		(fp_line
			(start 0.67945 0.3048)
			(end 0.67945 -0.305054)
			(stroke
				(width 0.1)
				(type default)
			)
			(layer "B.Fab")
		)
		(pad "1" smd circle
			(at 0.40005 0 180)
			(size 0 0)
			(layers "B.Cu" "B.Mask" "B.Paste")
			(net "PVDD11_S3_P0")
		)
		(pad "2" smd circle
			(at -0.40005 0 180)
			(size 0 0)
			(layers "B.Cu" "B.Mask" "B.Paste")
			(net "GND")
		)
	)
	(footprint ""
		(layer "B.Cu")
		(at 239.724692 -422.849548 -90)
		(property "Reference" "R2905"
			(at 0 0 90)
			(layer "B.SilkS")
			(hide yes)
			(effects
				(font
					(size 1.27 1.27)
				)
				(justify mirror)
			)
		)
		(property "Value" ""
			(at 0 0 90)
			(layer "B.Fab")
			(effects
				(font
					(size 1.27 1.27)
				)
				(justify mirror)
			)
		)
		(duplicate_pad_numbers_are_jumpers no)
		(fp_line
			(start -0.7874 0.4064)
			(end 0.7874 0.4064)
			(stroke
				(width 0.1524)
				(type default)
			)
			(layer "B.SilkS")
		)
		(fp_line
			(start 0.7874 0.4064)
			(end 0.7874 -0.4064)
			(stroke
				(width 0.1524)
				(type default)
			)
			(layer "B.SilkS")
		)
		(fp_line
			(start -0.7874 -0.4064)
			(end -0.7874 0.4064)
			(stroke
				(width 0.1524)
				(type default)
			)
			(layer "B.SilkS")
		)
		(fp_line
			(start 0.7874 -0.4064)
			(end -0.7874 -0.4064)
			(stroke
				(width 0.1524)
				(type default)
			)
			(layer "B.SilkS")
		)
		(fp_line
			(start -0.67945 0.3048)
			(end -0.120396 0.3048)
			(stroke
				(width 0.1)
				(type default)
			)
			(layer "B.Fab")
		)
		(fp_line
			(start -0.120396 0.3048)
			(end -0.120396 0.2794)
			(stroke
				(width 0.1)
				(type default)
			)
			(layer "B.Fab")
		)
		(fp_line
			(start 0.12065 0.3048)
			(end 0.67945 0.3048)
			(stroke
				(width 0.1)
				(type default)
			)
			(layer "B.Fab")
		)
		(fp_line
			(start 0.67945 0.3048)
			(end 0.67945 -0.305054)
			(stroke
				(width 0.1)
				(type default)
			)
			(layer "B.Fab")
		)
		(fp_line
			(start -0.120396 0.2794)
			(end 0.12065 0.2794)
			(stroke
				(width 0.1)
				(type default)
			)
			(layer "B.Fab")
		)
		(fp_line
			(start 0.12065 0.2794)
			(end 0.12065 0.3048)
			(stroke
				(width 0.1)
				(type default)
			)
			(layer "B.Fab")
		)
		(fp_line
			(start -0.12065 -0.2794)
			(end -0.12065 -0.3048)
			(stroke
				(width 0.1)
				(type default)
			)
			(layer "B.Fab")
		)
		(fp_line
			(start 0.12065 -0.2794)
			(end -0.12065 -0.2794)
			(stroke
				(width 0.1)
				(type default)
			)
			(layer "B.Fab")
		)
		(fp_line
			(start -0.67945 -0.3048)
			(end -0.67945 0.3048)
			(stroke
				(width 0.1)
				(type default)
			)
			(layer "B.Fab")
		)
		(fp_line
			(start -0.12065 -0.3048)
			(end -0.67945 -0.3048)
			(stroke
				(width 0.1)
				(type default)
			)
			(layer "B.Fab")
		)
		(fp_line
			(start 0.12065 -0.305054)
			(end 0.12065 -0.2794)
			(stroke
				(width 0.1)
				(type default)
			)
			(layer "B.Fab")
		)
		(fp_line
			(start 0.67945 -0.305054)
			(end 0.12065 -0.305054)
			(stroke
				(width 0.1)
				(type default)
			)
			(layer "B.Fab")
		)
		(pad "1" smd circle
			(at 0.40005 0 90)
			(size 0 0)
			(layers "B.Cu" "B.Mask" "B.Paste")
			(net "RST_SMB_SWITCH_N")
		)
		(pad "2" smd circle
			(at -0.40005 0 90)
			(size 0 0)
			(layers "B.Cu" "B.Mask" "B.Paste")
			(net "RST_SMB_SWITCH_R_N")
		)
	)
	(footprint ""
		(layer "B.Cu")
		(at 83.910424 -408.517344 90)
		(property "Reference" "C6683"
			(at 0 0 90)
			(layer "B.SilkS")
			(hide yes)
			(effects
				(font
					(size 1.27 1.27)
				)
				(justify mirror)
			)
		)
		(property "Value" ""
			(at 0 0 90)
			(layer "B.Fab")
			(effects
				(font
					(size 1.27 1.27)
				)
				(justify mirror)
			)
		)
		(duplicate_pad_numbers_are_jumpers no)
		(fp_line
			(start 0.299974 -0.150114)
			(end -0.299974 -0.150114)
			(stroke
				(width 0.1)
				(type default)
			)
			(layer "B.Fab")
		)
		(fp_line
			(start -0.299974 -0.150114)
			(end -0.299974 0.150114)
			(stroke
				(width 0.1)
				(type default)
			)
			(layer "B.Fab")
		)
		(fp_line
			(start 0.299974 0.150114)
			(end 0.299974 -0.150114)
			(stroke
				(width 0.1)
				(type default)
			)
			(layer "B.Fab")
		)
		(fp_line
			(start -0.299974 0.150114)
			(end 0.299974 0.150114)
			(stroke
				(width 0.1)
				(type default)
			)
			(layer "B.Fab")
		)
		(pad "1" smd rect
			(at 0.2667 0 270)
			(size 0.3048 0.381)
			(layers "B.Cu" "B.Mask" "B.Paste")
			(net "P5E_CPU1_P1_TX_BUF_C_DP<11>")
		)
		(pad "2" smd rect
			(at -0.2667 0 270)
			(size 0.3048 0.381)
			(layers "B.Cu" "B.Mask" "B.Paste")
			(net "P5E_CPU1_P1_TX_BUF_DP<11>")
		)
	)
)
